FILE_TYPE = CONNECTIVITY;
{Allegro Design Entry HDL 17.4-2019 S026 (4007227) 1/17/2022}
"PAGE_NUMBER" = 21;
0"NC";
1"M_L_CPU0_SA_DQ<31:0>";
2"M_L_CPU0_SB_DQ<31:0>";
3"M_L_CPU0_SA_CB<7:0>";
4"M_L_CPU0_SB_CB<7:0>";
5"M_L_CPU0_SA_DQS_DP<9:0>";
6"M_L_CPU0_SA_DQS_DN<9:0>";
7"M_L_CPU0_SB_DQS_DP<9:0>";
8"M_L_CPU0_SB_DQS_DN<9:0>";
9"M_L_CPU0_SB_CA<6:0>";
10"M_L_CPU0_SA_CA<6:0>";
11"M_L_CPU0_ALERT_N";
12"M_L_CPU0_ALERT_R_N";
13"TP_M_L_CPU0_SA_TEST39L";
14"M_L_CPU0_CLK_DP<0>";
15"M_L_CPU0_CLK_DN<0>";
16"M_L_CPU0_SA_CS_N<0>";
17"M_L_CPU0_SA_PAR";
18"M_L_CPU0_SA_RSP<0>";
19"M_L_CPU0_SA_CS_N<1>";
20"M_L_CPU0_SB_CS_N<0>";
21"M_L_CPU0_SB_CS_N<1>";
22"M_L_CPU0_SB_RSP<0>";
23"M_L_CPU0_SB_PAR";
24"M_L_CPU0_RESET_N";
25"M_L_CPU0_SA_CA<1>";
26"M_L_CPU0_SB_CA<0>";
27"M_L_CPU0_SA_CA<0>";
28"M_L_CPU0_SB_CA<6>";
29"M_L_CPU0_SA_CA<6>";
30"M_L_CPU0_SB_CA<5>";
31"M_L_CPU0_SA_CA<5>";
32"M_L_CPU0_SB_CA<4>";
33"M_L_CPU0_SA_CA<4>";
34"M_L_CPU0_SB_CA<3>";
35"M_L_CPU0_SA_CA<3>";
36"M_L_CPU0_SB_CA<2>";
37"M_L_CPU0_SA_CA<2>";
38"M_L_CPU0_SB_CA<1>";
39"M_L_CPU0_SB_DQS_DN<9>";
40"M_L_CPU0_SB_DQS_DP<9>";
41"M_L_CPU0_SB_DQS_DN<8>";
42"M_L_CPU0_SB_DQS_DN<7>";
43"M_L_CPU0_SB_DQS_DN<6>";
44"M_L_CPU0_SB_DQS_DN<5>";
45"M_L_CPU0_SB_DQS_DN<4>";
46"M_L_CPU0_SA_DQS_DN<9>";
47"M_L_CPU0_SB_DQS_DN<3>";
48"M_L_CPU0_SB_DQS_DN<2>";
49"M_L_CPU0_SB_DQS_DN<1>";
50"M_L_CPU0_SB_DQS_DN<0>";
51"M_L_CPU0_SB_DQS_DP<4>";
52"M_L_CPU0_SB_DQS_DP<8>";
53"M_L_CPU0_SB_DQS_DP<7>";
54"M_L_CPU0_SB_DQS_DP<6>";
55"M_L_CPU0_SB_DQS_DP<5>";
56"M_L_CPU0_SA_DQS_DP<9>";
57"M_L_CPU0_SB_DQS_DP<3>";
58"M_L_CPU0_SB_DQS_DP<2>";
59"M_L_CPU0_SB_DQS_DP<1>";
60"M_L_CPU0_SB_DQS_DP<0>";
61"M_L_CPU0_SA_DQS_DN<8>";
62"M_L_CPU0_SA_DQS_DN<7>";
63"M_L_CPU0_SA_DQS_DN<6>";
64"M_L_CPU0_SA_DQS_DN<5>";
65"M_L_CPU0_SA_DQS_DN<4>";
66"M_L_CPU0_SA_DQS_DN<3>";
67"M_L_CPU0_SA_DQS_DN<2>";
68"M_L_CPU0_SA_DQS_DN<1>";
69"M_L_CPU0_SA_DQS_DN<0>";
70"M_L_CPU0_SA_DQS_DP<8>";
71"M_L_CPU0_SA_DQS_DP<7>";
72"M_L_CPU0_SA_DQS_DP<6>";
73"M_L_CPU0_SA_DQS_DP<5>";
74"M_L_CPU0_SA_DQS_DP<4>";
75"M_L_CPU0_SA_DQS_DP<3>";
76"M_L_CPU0_SA_DQS_DP<2>";
77"M_L_CPU0_SA_DQS_DP<1>";
78"M_L_CPU0_SA_DQS_DP<0>";
79"M_L_CPU0_SB_CB<7>";
80"M_L_CPU0_SB_CB<6>";
81"M_L_CPU0_SB_CB<5>";
82"M_L_CPU0_SB_CB<4>";
83"M_L_CPU0_SB_CB<3>";
84"M_L_CPU0_SB_CB<2>";
85"M_L_CPU0_SB_CB<1>";
86"M_L_CPU0_SB_CB<0>";
87"M_L_CPU0_SA_CB<1>";
88"M_L_CPU0_SA_CB<0>";
89"M_L_CPU0_SB_DQ<29>";
90"M_L_CPU0_SB_DQ<28>";
91"M_L_CPU0_SB_DQ<27>";
92"M_L_CPU0_SB_DQ<26>";
93"M_L_CPU0_SB_DQ<25>";
94"M_L_CPU0_SB_DQ<24>";
95"M_L_CPU0_SB_DQ<23>";
96"M_L_CPU0_SB_DQ<22>";
97"M_L_CPU0_SA_CB<7>";
98"M_L_CPU0_SB_DQ<21>";
99"M_L_CPU0_SA_CB<6>";
100"M_L_CPU0_SB_DQ<31>";
101"M_L_CPU0_SA_CB<5>";
102"M_L_CPU0_SB_DQ<30>";
103"M_L_CPU0_SA_CB<4>";
104"M_L_CPU0_SA_CB<3>";
105"M_L_CPU0_SA_CB<2>";
106"M_L_CPU0_SB_DQ<3>";
107"M_L_CPU0_SB_DQ<19>";
108"M_L_CPU0_SB_DQ<18>";
109"M_L_CPU0_SB_DQ<17>";
110"M_L_CPU0_SB_DQ<16>";
111"M_L_CPU0_SB_DQ<15>";
112"M_L_CPU0_SB_DQ<14>";
113"M_L_CPU0_SB_DQ<13>";
114"M_L_CPU0_SB_DQ<12>";
115"M_L_CPU0_SB_DQ<11>";
116"M_L_CPU0_SB_DQ<9>";
117"M_L_CPU0_SB_DQ<10>";
118"M_L_CPU0_SB_DQ<8>";
119"M_L_CPU0_SB_DQ<20>";
120"M_L_CPU0_SB_DQ<7>";
121"M_L_CPU0_SB_DQ<6>";
122"M_L_CPU0_SB_DQ<5>";
123"M_L_CPU0_SB_DQ<4>";
124"M_L_CPU0_SA_DQ<21>";
125"M_L_CPU0_SA_DQ<20>";
126"M_L_CPU0_SA_DQ<31>";
127"M_L_CPU0_SB_DQ<2>";
128"M_L_CPU0_SA_DQ<30>";
129"M_L_CPU0_SB_DQ<1>";
130"M_L_CPU0_SB_DQ<0>";
131"M_L_CPU0_SA_DQ<19>";
132"M_L_CPU0_SA_DQ<18>";
133"M_L_CPU0_SA_DQ<29>";
134"M_L_CPU0_SA_DQ<17>";
135"M_L_CPU0_SA_DQ<28>";
136"M_L_CPU0_SA_DQ<16>";
137"M_L_CPU0_SA_DQ<27>";
138"M_L_CPU0_SA_DQ<26>";
139"M_L_CPU0_SA_DQ<25>";
140"M_L_CPU0_SA_DQ<24>";
141"M_L_CPU0_SA_DQ<23>";
142"M_L_CPU0_SA_DQ<22>";
143"M_L_CPU0_SA_DQ<4>";
144"M_L_CPU0_SA_DQ<10>";
145"M_L_CPU0_SA_DQ<3>";
146"M_L_CPU0_SA_DQ<2>";
147"M_L_CPU0_SA_DQ<1>";
148"M_L_CPU0_SA_DQ<0>";
149"M_L_CPU0_SA_DQ<9>";
150"M_L_CPU0_SA_DQ<15>";
151"M_L_CPU0_SA_DQ<8>";
152"M_L_CPU0_SA_DQ<14>";
153"M_L_CPU0_SA_DQ<7>";
154"M_L_CPU0_SA_DQ<13>";
155"M_L_CPU0_SA_DQ<6>";
156"M_L_CPU0_SA_DQ<12>";
157"M_L_CPU0_SA_DQ<5>";
158"M_L_CPU0_SA_DQ<11>";
%"GENOA_SP5"
"35","(-4500,3625)","0","pure_quanta","I159";
;
LOCATION"U25"
$SEC"35"
CDS_SEC"35"
PART_TYPE"SMLF"
MATERIAL"IO"
VALUE"SOCKET6096_13568-001"
CDS_LIB"pure_quanta"
CDS_LMAN_SYM_OUTLINE"-650,2525,650,-2525"
NEEDS_NO_SIZE"TRUE"
PART_NUMBER"DGA^6000030";
"TEST39L"
$PN"BF11"13;
"MLA_CA1"
$PN"AY9"25;
"MLA_CHECK1"
$PN"AK11"87;
"MLA_DATA4"
$PN"J9"143;
"MLA_DATA10"
$PN"M9"144;
"MLA_DATA21"
$PN"AB11"124;
"MLB_CA0"
$PN"BG10"26;
"MLB_DATA3"
$PN"CD11"106;
"MLB_DQS_H4"
$PN"BY11"51;
"MLB_DQS_L8"
$PN"DC10"41;
"MLA_CA0"
$PN"AW9"27;
"MLA_CHECK0"
$PN"AJ9"88;
"MLA_DATA3"
$PN"G10"145;
"MLA_DATA20"
$PN"AA9"125;
"MLA_DATA31"
$PN"AJ10"126;
"MLA_DQS_H9"
$PN"AN10"56;
"MLB_DATA2"
$PN"CC9"127;
"MLB_DQS_H3"
$PN"DB9"57;
"MLB_DQS_L7"
$PN"CU10"42;
"MLA1_CS_L1"
$PN"AW10"0;
"MLA_DATA2"
$PN"F9"146;
"MLA_DATA30"
$PN"AH9"128;
"MLA_DQS_H8"
$PN"AG10"70;
"MLB_DATA1"
$PN"CC10"129;
"MLB_DATA19"
$PN"CT11"107;
"MLB_DQS_H2"
$PN"CT9"58;
"MLB_DQS_L6"
$PN"CL10"43;
"MLA0_CS_L1"
$PN"AV11"19;
"MLA1_CS_L0"
$PN"AV9"0;
"MLA_DATA1"
$PN"F11"147;
"MLA_DQS_H7"
$PN"AA10"71;
"MLB_DATA0"
$PN"CB9"130;
"MLB_DATA18"
$PN"CR9"108;
"MLB_DATA29"
$PN"DE10"89;
"MLB_DQS_H1"
$PN"CK9"59;
"MLB_DQS_L5"
$PN"CE10"44;
"ML1_CLK_L"
$PN"BG9"0;
"MLA0_CS_L0"
$PN"AU9"16;
"MLA_DATA0"
$PN"E9"148;
"MLA_DQS_H6"
$PN"R10"72;
"MLB_DATA17"
$PN"CR10"109;
"MLB_DATA28"
$PN"DD9"90;
"MLB_DQS_H0"
$PN"CD9"60;
"MLB_DQS_L4"
$PN"BW10"45;
"MLB_PAR"
$PN"BL10"23;
"ML0_CLK_L"
$PN"BD9"15;
"MLA_DQS_H5"
$PN"J10"73;
"MLA_DQS_L9"
$PN"AM11"46;
"MLA_PAR"
$PN"BC10"17;
"MLB1_RSP_L"
$PN"BR9"0;
"MLB_CHECK7"
$PN"BV11"79;
"MLB_DATA16"
$PN"CP9"110;
"MLB_DATA27"
$PN"DB11"91;
"MLB_DQS_L3"
$PN"DC9"47;
"MLA_DQS_H4"
$PN"AL9"74;
"MLA_DQS_L8"
$PN"AF11"61;
"MLB0_RSP_L"
$PN"BP9"22;
"MLB_CHECK6"
$PN"BU9"80;
"MLB_DATA15"
$PN"CP11"111;
"MLB_DATA26"
$PN"DA9"92;
"MLB_DQS_L2"
$PN"CU9"48;
"MLA_DQS_H3"
$PN"AE9"75;
"MLA_DQS_L7"
$PN"Y11"62;
"MLB_CHECK5"
$PN"BU10"81;
"MLB_DATA14"
$PN"CN9"112;
"MLB_DATA25"
$PN"DA10"93;
"MLB_DQS_L1"
$PN"CL9"49;
"ML1_CLK_H"
$PN"BF9"0;
"MLA_DATA19"
$PN"W10"131;
"MLA_DQS_H2"
$PN"W9"76;
"MLA_DQS_L6"
$PN"P11"63;
"MLB_CHECK4"
$PN"BT9"82;
"MLB_DATA13"
$PN"CN10"113;
"MLB_DATA24"
$PN"CY9"94;
"MLB_DQS_L0"
$PN"CE9"50;
"ML0_CLK_H"
$PN"BC9"14;
"MLA_DATA18"
$PN"V9"132;
"MLA_DATA29"
$PN"AH11"133;
"MLA_DQS_H1"
$PN"N9"77;
"MLA_DQS_L5"
$PN"H11"64;
"MLB_CHECK3"
$PN"CB11"83;
"MLB_DATA12"
$PN"CM9"114;
"MLB_DATA23"
$PN"CY11"95;
"MLA_DATA17"
$PN"V11"134;
"MLA_DATA28"
$PN"AG9"135;
"MLA_DQS_H0"
$PN"G9"78;
"MLA_DQS_L4"
$PN"AM9"65;
"MLB_CHECK2"
$PN"CA9"84;
"MLB_DATA11"
$PN"CK11"115;
"MLB_DATA22"
$PN"CW9"96;
"ML_ALERT_L"
$PN"AT11"12;
"MLA1_RSP_L"
$PN"BP11"0;
"MLA_CHECK7"
$PN"AR10"97;
"MLA_DATA16"
$PN"U9"136;
"MLA_DATA27"
$PN"AE10"137;
"MLA_DQS_L3"
$PN"AF9"66;
"MLB_CA6"
$PN"BK9"28;
"MLB_CHECK1"
$PN"CA10"85;
"MLB_DATA9"
$PN"CJ10"116;
"MLB_DATA10"
$PN"CJ9"117;
"MLB_DATA21"
$PN"CW10"98;
"MLA0_RSP_L"
$PN"BN10"18;
"MLA_CA6"
$PN"BB11"29;
"MLA_CHECK6"
$PN"AP9"99;
"MLA_DATA9"
$PN"M11"149;
"MLA_DATA15"
$PN"U10"150;
"MLA_DATA26"
$PN"AD9"138;
"MLA_DQS_L2"
$PN"Y9"67;
"MLB_CA5"
$PN"BK11"30;
"MLB_CHECK0"
$PN"BY9"86;
"MLB_DATA8"
$PN"CH9"118;
"MLB_DATA20"
$PN"CV9"119;
"MLB_DATA31"
$PN"DF9"100;
"MLB_DQS_H9"
$PN"BV9"40;
"MLA_CA5"
$PN"BB9"31;
"MLA_CHECK5"
$PN"AP11"101;
"MLA_DATA8"
$PN"L9"151;
"MLA_DATA14"
$PN"T9"152;
"MLA_DATA25"
$PN"AD11"139;
"MLA_DQS_L1"
$PN"P9"68;
"MLB1_CS_L1"
$PN"BM9"0;
"MLB_CA4"
$PN"BJ10"32;
"MLB_DATA7"
$PN"CH11"120;
"MLB_DATA30"
$PN"DE9"102;
"MLB_DQS_H8"
$PN"DD11"52;
"MLA_CA4"
$PN"BA9"33;
"MLA_CHECK4"
$PN"AN9"103;
"MLA_DATA7"
$PN"L10"153;
"MLA_DATA13"
$PN"T11"154;
"MLA_DATA24"
$PN"AC9"140;
"MLA_DQS_L0"
$PN"H9"69;
"MLB0_CS_L1"
$PN"BN9"21;
"MLB1_CS_L0"
$PN"BL9"0;
"MLB_CA3"
$PN"BJ9"34;
"MLB_DATA6"
$PN"CG9"121;
"MLB_DQS_H7"
$PN"CV11"53;
"MLA_CA3"
$PN"BA10"35;
"MLA_CHECK3"
$PN"AL10"104;
"MLA_DATA6"
$PN"K9"155;
"MLA_DATA12"
$PN"R9"156;
"MLA_DATA23"
$PN"AC10"141;
"MLB0_CS_L0"
$PN"BM11"20;
"MLB_CA2"
$PN"BH9"36;
"MLB_DATA5"
$PN"CG10"122;
"MLB_DQS_H6"
$PN"CM11"54;
"ML_RESET_L"
$PN"AU10"24;
"MLA_CA2"
$PN"AY11"37;
"MLA_CHECK2"
$PN"AK9"105;
"MLA_DATA5"
$PN"K11"157;
"MLA_DATA11"
$PN"N10"158;
"MLA_DATA22"
$PN"AB9"142;
"MLB_CA1"
$PN"BH11"38;
"MLB_DATA4"
$PN"CF9"123;
"MLB_DQS_H5"
$PN"CF11"55;
"MLB_DQS_L9"
$PN"BW9"39;
%"TAP"
"1","(-3225,5950)","0","mstr_standard","I162";
;
CDS_LIB"mstr_standard"
BODY_TYPE"PLUMBING"
HDL_TAP"TRUE";
"B \NAC \NWC"1;
"S \NAC"
BN"1"147;
%"TAP"
"1","(-3225,6000)","0","mstr_standard","I163";
;
CDS_LIB"mstr_standard"
BODY_TYPE"PLUMBING"
HDL_TAP"TRUE";
"B \NAC \NWC"1;
"S \NAC"
BN"0"148;
%"TAP"
"1","(-3225,5900)","0","mstr_standard","I164";
;
CDS_LIB"mstr_standard"
BODY_TYPE"PLUMBING"
HDL_TAP"TRUE";
"B \NAC \NWC"1;
"S \NAC"
BN"2"146;
%"TAP"
"1","(-3225,5850)","0","mstr_standard","I165";
;
CDS_LIB"mstr_standard"
BODY_TYPE"PLUMBING"
HDL_TAP"TRUE";
"B \NAC \NWC"1;
"S \NAC"
BN"3"145;
%"TAP"
"1","(-3225,5800)","0","mstr_standard","I166";
;
CDS_LIB"mstr_standard"
BODY_TYPE"PLUMBING"
HDL_TAP"TRUE";
"B \NAC \NWC"1;
"S \NAC"
BN"4"143;
%"TAP"
"1","(-3225,5750)","0","mstr_standard","I167";
;
CDS_LIB"mstr_standard"
BODY_TYPE"PLUMBING"
HDL_TAP"TRUE";
"B \NAC \NWC"1;
"S \NAC"
BN"5"157;
%"TAP"
"1","(-3225,5700)","0","mstr_standard","I168";
;
CDS_LIB"mstr_standard"
BODY_TYPE"PLUMBING"
HDL_TAP"TRUE";
"B \NAC \NWC"1;
"S \NAC"
BN"6"155;
%"TAP"
"1","(-3225,5650)","0","mstr_standard","I169";
;
CDS_LIB"mstr_standard"
BODY_TYPE"PLUMBING"
HDL_TAP"TRUE";
"B \NAC \NWC"1;
"S \NAC"
BN"7"153;
%"TAP"
"1","(-3225,5450)","0","mstr_standard","I170";
;
CDS_LIB"mstr_standard"
BODY_TYPE"PLUMBING"
HDL_TAP"TRUE";
"B \NAC \NWC"1;
"S \NAC"
BN"10"144;
%"TAP"
"1","(-3225,5500)","0","mstr_standard","I171";
;
CDS_LIB"mstr_standard"
BODY_TYPE"PLUMBING"
HDL_TAP"TRUE";
"B \NAC \NWC"1;
"S \NAC"
BN"9"149;
%"TAP"
"1","(-3225,5550)","0","mstr_standard","I172";
;
CDS_LIB"mstr_standard"
BODY_TYPE"PLUMBING"
HDL_TAP"TRUE";
"B \NAC \NWC"1;
"S \NAC"
BN"8"151;
%"TAP"
"1","(-3225,5400)","0","mstr_standard","I173";
;
CDS_LIB"mstr_standard"
BODY_TYPE"PLUMBING"
HDL_TAP"TRUE";
"B \NAC \NWC"1;
"S \NAC"
BN"11"158;
%"TAP"
"1","(-3225,5300)","0","mstr_standard","I174";
;
CDS_LIB"mstr_standard"
BODY_TYPE"PLUMBING"
HDL_TAP"TRUE";
"B \NAC \NWC"1;
"S \NAC"
BN"13"154;
%"TAP"
"1","(-3225,5350)","0","mstr_standard","I175";
;
CDS_LIB"mstr_standard"
BODY_TYPE"PLUMBING"
HDL_TAP"TRUE";
"B \NAC \NWC"1;
"S \NAC"
BN"12"156;
%"TAP"
"1","(-3225,5200)","0","mstr_standard","I176";
;
CDS_LIB"mstr_standard"
BODY_TYPE"PLUMBING"
HDL_TAP"TRUE";
"B \NAC \NWC"1;
"S \NAC"
BN"15"150;
%"TAP"
"1","(-3225,5250)","0","mstr_standard","I177";
;
CDS_LIB"mstr_standard"
BODY_TYPE"PLUMBING"
HDL_TAP"TRUE";
"B \NAC \NWC"1;
"S \NAC"
BN"14"152;
%"TAP"
"1","(-3225,5100)","0","mstr_standard","I178";
;
CDS_LIB"mstr_standard"
BODY_TYPE"PLUMBING"
HDL_TAP"TRUE";
"B \NAC \NWC"1;
"S \NAC"
BN"16"136;
%"TAP"
"1","(-3225,5050)","0","mstr_standard","I179";
;
CDS_LIB"mstr_standard"
BODY_TYPE"PLUMBING"
HDL_TAP"TRUE";
"B \NAC \NWC"1;
"S \NAC"
BN"17"134;
%"TAP"
"1","(-3225,5000)","0","mstr_standard","I180";
;
CDS_LIB"mstr_standard"
BODY_TYPE"PLUMBING"
HDL_TAP"TRUE";
"B \NAC \NWC"1;
"S \NAC"
BN"18"132;
%"TAP"
"1","(-3225,4950)","0","mstr_standard","I181";
;
CDS_LIB"mstr_standard"
BODY_TYPE"PLUMBING"
HDL_TAP"TRUE";
"B \NAC \NWC"1;
"S \NAC"
BN"19"131;
%"TAP"
"1","(-3225,4900)","0","mstr_standard","I182";
;
CDS_LIB"mstr_standard"
BODY_TYPE"PLUMBING"
HDL_TAP"TRUE";
"B \NAC \NWC"1;
"S \NAC"
BN"20"125;
%"TAP"
"1","(-3225,4800)","0","mstr_standard","I183";
;
CDS_LIB"mstr_standard"
BODY_TYPE"PLUMBING"
HDL_TAP"TRUE";
"B \NAC \NWC"1;
"S \NAC"
BN"22"142;
%"TAP"
"1","(-3225,4850)","0","mstr_standard","I184";
;
CDS_LIB"mstr_standard"
BODY_TYPE"PLUMBING"
HDL_TAP"TRUE";
"B \NAC \NWC"1;
"S \NAC"
BN"21"124;
%"TAP"
"1","(-3225,4750)","0","mstr_standard","I185";
;
CDS_LIB"mstr_standard"
BODY_TYPE"PLUMBING"
HDL_TAP"TRUE";
"B \NAC \NWC"1;
"S \NAC"
BN"23"141;
%"TAP"
"1","(-3225,4650)","0","mstr_standard","I186";
;
CDS_LIB"mstr_standard"
BODY_TYPE"PLUMBING"
HDL_TAP"TRUE";
"B \NAC \NWC"1;
"S \NAC"
BN"24"140;
%"TAP"
"1","(-3225,4550)","0","mstr_standard","I187";
;
CDS_LIB"mstr_standard"
BODY_TYPE"PLUMBING"
HDL_TAP"TRUE";
"B \NAC \NWC"1;
"S \NAC"
BN"26"138;
%"TAP"
"1","(-3225,4600)","0","mstr_standard","I188";
;
CDS_LIB"mstr_standard"
BODY_TYPE"PLUMBING"
HDL_TAP"TRUE";
"B \NAC \NWC"1;
"S \NAC"
BN"25"139;
%"TAP"
"1","(-3225,4500)","0","mstr_standard","I189";
;
CDS_LIB"mstr_standard"
BODY_TYPE"PLUMBING"
HDL_TAP"TRUE";
"B \NAC \NWC"1;
"S \NAC"
BN"27"137;
%"TAP"
"1","(-3225,4450)","0","mstr_standard","I190";
;
CDS_LIB"mstr_standard"
BODY_TYPE"PLUMBING"
HDL_TAP"TRUE";
"B \NAC \NWC"1;
"S \NAC"
BN"28"135;
%"TAP"
"1","(-3225,4400)","0","mstr_standard","I191";
;
CDS_LIB"mstr_standard"
BODY_TYPE"PLUMBING"
HDL_TAP"TRUE";
"B \NAC \NWC"1;
"S \NAC"
BN"29"133;
%"TAP"
"1","(-3225,4300)","0","mstr_standard","I192";
;
CDS_LIB"mstr_standard"
BODY_TYPE"PLUMBING"
HDL_TAP"TRUE";
"B \NAC \NWC"1;
"S \NAC"
BN"31"126;
%"TAP"
"1","(-3225,4350)","0","mstr_standard","I193";
;
CDS_LIB"mstr_standard"
BODY_TYPE"PLUMBING"
HDL_TAP"TRUE";
"B \NAC \NWC"1;
"S \NAC"
BN"30"128;
%"TAP"
"1","(-3225,4150)","0","mstr_standard","I194";
;
CDS_LIB"mstr_standard"
BODY_TYPE"PLUMBING"
HDL_TAP"TRUE";
"B \NAC \NWC"2;
"S \NAC"
BN"1"129;
%"TAP"
"1","(-3225,4200)","0","mstr_standard","I195";
;
CDS_LIB"mstr_standard"
BODY_TYPE"PLUMBING"
HDL_TAP"TRUE";
"B \NAC \NWC"2;
"S \NAC"
BN"0"130;
%"TAP"
"1","(-3225,4100)","0","mstr_standard","I196";
;
CDS_LIB"mstr_standard"
BODY_TYPE"PLUMBING"
HDL_TAP"TRUE";
"B \NAC \NWC"2;
"S \NAC"
BN"2"127;
%"TAP"
"1","(-3225,4050)","0","mstr_standard","I198";
;
CDS_LIB"mstr_standard"
BODY_TYPE"PLUMBING"
HDL_TAP"TRUE";
"B \NAC \NWC"2;
"S \NAC"
BN"3"106;
%"TAP"
"1","(-3225,4000)","0","mstr_standard","I199";
;
CDS_LIB"mstr_standard"
BODY_TYPE"PLUMBING"
HDL_TAP"TRUE";
"B \NAC \NWC"2;
"S \NAC"
BN"4"123;
%"TAP"
"1","(-3225,3950)","0","mstr_standard","I200";
;
CDS_LIB"mstr_standard"
BODY_TYPE"PLUMBING"
HDL_TAP"TRUE";
"B \NAC \NWC"2;
"S \NAC"
BN"5"122;
%"TAP"
"1","(-3225,3900)","0","mstr_standard","I201";
;
CDS_LIB"mstr_standard"
BODY_TYPE"PLUMBING"
HDL_TAP"TRUE";
"B \NAC \NWC"2;
"S \NAC"
BN"6"121;
%"TAP"
"1","(-3225,3850)","0","mstr_standard","I202";
;
CDS_LIB"mstr_standard"
BODY_TYPE"PLUMBING"
HDL_TAP"TRUE";
"B \NAC \NWC"2;
"S \NAC"
BN"7"120;
%"TAP"
"1","(-3225,3650)","0","mstr_standard","I203";
;
CDS_LIB"mstr_standard"
BODY_TYPE"PLUMBING"
HDL_TAP"TRUE";
"B \NAC \NWC"2;
"S \NAC"
BN"10"117;
%"TAP"
"1","(-3225,3700)","0","mstr_standard","I204";
;
CDS_LIB"mstr_standard"
BODY_TYPE"PLUMBING"
HDL_TAP"TRUE";
"B \NAC \NWC"2;
"S \NAC"
BN"9"116;
%"TAP"
"1","(-3225,3750)","0","mstr_standard","I205";
;
CDS_LIB"mstr_standard"
BODY_TYPE"PLUMBING"
HDL_TAP"TRUE";
"B \NAC \NWC"2;
"S \NAC"
BN"8"118;
%"TAP"
"1","(-3225,3600)","0","mstr_standard","I206";
;
CDS_LIB"mstr_standard"
BODY_TYPE"PLUMBING"
HDL_TAP"TRUE";
"B \NAC \NWC"2;
"S \NAC"
BN"11"115;
%"TAP"
"1","(-3225,3550)","0","mstr_standard","I207";
;
CDS_LIB"mstr_standard"
BODY_TYPE"PLUMBING"
HDL_TAP"TRUE";
"B \NAC \NWC"2;
"S \NAC"
BN"12"114;
%"TAP"
"1","(-3225,3450)","0","mstr_standard","I208";
;
CDS_LIB"mstr_standard"
BODY_TYPE"PLUMBING"
HDL_TAP"TRUE";
"B \NAC \NWC"2;
"S \NAC"
BN"14"112;
%"TAP"
"1","(-3225,3400)","0","mstr_standard","I209";
;
CDS_LIB"mstr_standard"
BODY_TYPE"PLUMBING"
HDL_TAP"TRUE";
"B \NAC \NWC"2;
"S \NAC"
BN"15"111;
%"TAP"
"1","(-3225,3500)","0","mstr_standard","I210";
;
CDS_LIB"mstr_standard"
BODY_TYPE"PLUMBING"
HDL_TAP"TRUE";
"B \NAC \NWC"2;
"S \NAC"
BN"13"113;
%"TAP"
"1","(-3225,3300)","0","mstr_standard","I211";
;
CDS_LIB"mstr_standard"
BODY_TYPE"PLUMBING"
HDL_TAP"TRUE";
"B \NAC \NWC"2;
"S \NAC"
BN"16"110;
%"TAP"
"1","(-3225,3250)","0","mstr_standard","I212";
;
CDS_LIB"mstr_standard"
BODY_TYPE"PLUMBING"
HDL_TAP"TRUE";
"B \NAC \NWC"2;
"S \NAC"
BN"17"109;
%"TAP"
"1","(-3225,3200)","0","mstr_standard","I213";
;
CDS_LIB"mstr_standard"
BODY_TYPE"PLUMBING"
HDL_TAP"TRUE";
"B \NAC \NWC"2;
"S \NAC"
BN"18"108;
%"TAP"
"1","(-3225,3150)","0","mstr_standard","I214";
;
CDS_LIB"mstr_standard"
BODY_TYPE"PLUMBING"
HDL_TAP"TRUE";
"B \NAC \NWC"2;
"S \NAC"
BN"19"107;
%"TAP"
"1","(-3225,3100)","0","mstr_standard","I215";
;
CDS_LIB"mstr_standard"
BODY_TYPE"PLUMBING"
HDL_TAP"TRUE";
"B \NAC \NWC"2;
"S \NAC"
BN"20"119;
%"TAP"
"1","(-3225,2850)","0","mstr_standard","I216";
;
CDS_LIB"mstr_standard"
BODY_TYPE"PLUMBING"
HDL_TAP"TRUE";
"B \NAC \NWC"2;
"S \NAC"
BN"24"94;
%"TAP"
"1","(-3225,3050)","0","mstr_standard","I217";
;
CDS_LIB"mstr_standard"
BODY_TYPE"PLUMBING"
HDL_TAP"TRUE";
"B \NAC \NWC"2;
"S \NAC"
BN"21"98;
%"TAP"
"1","(-3225,3000)","0","mstr_standard","I218";
;
CDS_LIB"mstr_standard"
BODY_TYPE"PLUMBING"
HDL_TAP"TRUE";
"B \NAC \NWC"2;
"S \NAC"
BN"22"96;
%"TAP"
"1","(-3225,2950)","0","mstr_standard","I219";
;
CDS_LIB"mstr_standard"
BODY_TYPE"PLUMBING"
HDL_TAP"TRUE";
"B \NAC \NWC"2;
"S \NAC"
BN"23"95;
%"TAP"
"1","(-3225,2800)","0","mstr_standard","I220";
;
CDS_LIB"mstr_standard"
BODY_TYPE"PLUMBING"
HDL_TAP"TRUE";
"B \NAC \NWC"2;
"S \NAC"
BN"25"93;
%"TAP"
"1","(-3225,2750)","0","mstr_standard","I221";
;
CDS_LIB"mstr_standard"
BODY_TYPE"PLUMBING"
HDL_TAP"TRUE";
"B \NAC \NWC"2;
"S \NAC"
BN"26"92;
%"TAP"
"1","(-3225,2700)","0","mstr_standard","I222";
;
CDS_LIB"mstr_standard"
BODY_TYPE"PLUMBING"
HDL_TAP"TRUE";
"B \NAC \NWC"2;
"S \NAC"
BN"27"91;
%"TAP"
"1","(-3225,2650)","0","mstr_standard","I223";
;
CDS_LIB"mstr_standard"
BODY_TYPE"PLUMBING"
HDL_TAP"TRUE";
"B \NAC \NWC"2;
"S \NAC"
BN"28"90;
%"TAP"
"1","(-3225,2600)","0","mstr_standard","I224";
;
CDS_LIB"mstr_standard"
BODY_TYPE"PLUMBING"
HDL_TAP"TRUE";
"B \NAC \NWC"2;
"S \NAC"
BN"29"89;
%"TAP"
"1","(-3225,2500)","0","mstr_standard","I225";
;
CDS_LIB"mstr_standard"
BODY_TYPE"PLUMBING"
HDL_TAP"TRUE";
"B \NAC \NWC"2;
"S \NAC"
BN"31"100;
%"TAP"
"1","(-3225,2550)","0","mstr_standard","I226";
;
CDS_LIB"mstr_standard"
BODY_TYPE"PLUMBING"
HDL_TAP"TRUE";
"B \NAC \NWC"2;
"S \NAC"
BN"30"102;
%"TAP"
"1","(-3225,2400)","0","mstr_standard","I227";
;
CDS_LIB"mstr_standard"
BODY_TYPE"PLUMBING"
HDL_TAP"TRUE";
"B \NAC \NWC"3;
"S \NAC"
BN"0"88;
%"TAP"
"1","(-3225,2350)","0","mstr_standard","I228";
;
CDS_LIB"mstr_standard"
BODY_TYPE"PLUMBING"
HDL_TAP"TRUE";
"B \NAC \NWC"3;
"S \NAC"
BN"1"87;
%"TAP"
"1","(-3225,2300)","0","mstr_standard","I229";
;
CDS_LIB"mstr_standard"
BODY_TYPE"PLUMBING"
HDL_TAP"TRUE";
"B \NAC \NWC"3;
"S \NAC"
BN"2"105;
%"TAP"
"1","(-3225,2250)","0","mstr_standard","I230";
;
CDS_LIB"mstr_standard"
BODY_TYPE"PLUMBING"
HDL_TAP"TRUE";
"B \NAC \NWC"3;
"S \NAC"
BN"3"104;
%"TAP"
"1","(-3225,2200)","0","mstr_standard","I231";
;
CDS_LIB"mstr_standard"
BODY_TYPE"PLUMBING"
HDL_TAP"TRUE";
"B \NAC \NWC"3;
"S \NAC"
BN"4"103;
%"TAP"
"1","(-3225,2100)","0","mstr_standard","I232";
;
CDS_LIB"mstr_standard"
BODY_TYPE"PLUMBING"
HDL_TAP"TRUE";
"B \NAC \NWC"3;
"S \NAC"
BN"6"99;
%"TAP"
"1","(-3225,2150)","0","mstr_standard","I233";
;
CDS_LIB"mstr_standard"
BODY_TYPE"PLUMBING"
HDL_TAP"TRUE";
"B \NAC \NWC"3;
"S \NAC"
BN"5"101;
%"TAP"
"1","(-3225,2050)","0","mstr_standard","I234";
;
CDS_LIB"mstr_standard"
BODY_TYPE"PLUMBING"
HDL_TAP"TRUE";
"B \NAC \NWC"3;
"S \NAC"
BN"7"97;
%"TAP"
"1","(-3225,1850)","0","mstr_standard","I236";
;
CDS_LIB"mstr_standard"
BODY_TYPE"PLUMBING"
HDL_TAP"TRUE";
"B \NAC \NWC"4;
"S \NAC"
BN"2"84;
%"TAP"
"1","(-3225,1900)","0","mstr_standard","I237";
;
CDS_LIB"mstr_standard"
BODY_TYPE"PLUMBING"
HDL_TAP"TRUE";
"B \NAC \NWC"4;
"S \NAC"
BN"1"85;
%"TAP"
"1","(-3225,1950)","0","mstr_standard","I238";
;
CDS_LIB"mstr_standard"
BODY_TYPE"PLUMBING"
HDL_TAP"TRUE";
"B \NAC \NWC"4;
"S \NAC"
BN"0"86;
%"TAP"
"1","(-3225,1800)","0","mstr_standard","I239";
;
CDS_LIB"mstr_standard"
BODY_TYPE"PLUMBING"
HDL_TAP"TRUE";
"B \NAC \NWC"4;
"S \NAC"
BN"3"83;
%"TAP"
"1","(-3225,1750)","0","mstr_standard","I240";
;
CDS_LIB"mstr_standard"
BODY_TYPE"PLUMBING"
HDL_TAP"TRUE";
"B \NAC \NWC"4;
"S \NAC"
BN"4"82;
%"TAP"
"1","(-3225,1600)","0","mstr_standard","I241";
;
CDS_LIB"mstr_standard"
BODY_TYPE"PLUMBING"
HDL_TAP"TRUE";
"B \NAC \NWC"4;
"S \NAC"
BN"7"79;
%"TAP"
"1","(-3225,1650)","0","mstr_standard","I242";
;
CDS_LIB"mstr_standard"
BODY_TYPE"PLUMBING"
HDL_TAP"TRUE";
"B \NAC \NWC"4;
"S \NAC"
BN"6"80;
%"TAP"
"1","(-3225,1700)","0","mstr_standard","I243";
;
CDS_LIB"mstr_standard"
BODY_TYPE"PLUMBING"
HDL_TAP"TRUE";
"B \NAC \NWC"4;
"S \NAC"
BN"5"81;
%"TAP"
"1","(-5650,6000)","2","mstr_standard","I244";
;
CDS_LIB"mstr_standard"
BODY_TYPE"PLUMBING"
HDL_TAP"TRUE";
"B \NAC \NWC"5;
"S \NAC"
BN"0"78;
%"TAP"
"1","(-5650,5900)","2","mstr_standard","I245";
;
CDS_LIB"mstr_standard"
BODY_TYPE"PLUMBING"
HDL_TAP"TRUE";
"B \NAC \NWC"5;
"S \NAC"
BN"1"77;
%"TAP"
"1","(-5650,5800)","2","mstr_standard","I246";
;
CDS_LIB"mstr_standard"
BODY_TYPE"PLUMBING"
HDL_TAP"TRUE";
"B \NAC \NWC"5;
"S \NAC"
BN"2"76;
%"TAP"
"1","(-5650,5700)","2","mstr_standard","I247";
;
CDS_LIB"mstr_standard"
BODY_TYPE"PLUMBING"
HDL_TAP"TRUE";
"B \NAC \NWC"5;
"S \NAC"
BN"3"75;
%"TAP"
"1","(-5650,5600)","2","mstr_standard","I248";
;
CDS_LIB"mstr_standard"
BODY_TYPE"PLUMBING"
HDL_TAP"TRUE";
"B \NAC \NWC"5;
"S \NAC"
BN"4"74;
%"TAP"
"1","(-5650,5400)","2","mstr_standard","I249";
;
CDS_LIB"mstr_standard"
BODY_TYPE"PLUMBING"
HDL_TAP"TRUE";
"B \NAC \NWC"5;
"S \NAC"
BN"6"72;
%"TAP"
"1","(-5650,5500)","2","mstr_standard","I250";
;
CDS_LIB"mstr_standard"
BODY_TYPE"PLUMBING"
HDL_TAP"TRUE";
"B \NAC \NWC"5;
"S \NAC"
BN"5"73;
%"TAP"
"1","(-5650,5300)","2","mstr_standard","I251";
;
CDS_LIB"mstr_standard"
BODY_TYPE"PLUMBING"
HDL_TAP"TRUE";
"B \NAC \NWC"5;
"S \NAC"
BN"7"71;
%"TAP"
"1","(-5650,5200)","2","mstr_standard","I252";
;
CDS_LIB"mstr_standard"
BODY_TYPE"PLUMBING"
HDL_TAP"TRUE";
"B \NAC \NWC"5;
"S \NAC"
BN"8"70;
%"TAP"
"1","(-5850,5950)","2","mstr_standard","I253";
;
CDS_LIB"mstr_standard"
BODY_TYPE"PLUMBING"
HDL_TAP"TRUE";
"B \NAC \NWC"6;
"S \NAC"
BN"0"69;
%"TAP"
"1","(-5850,5850)","2","mstr_standard","I254";
;
CDS_LIB"mstr_standard"
BODY_TYPE"PLUMBING"
HDL_TAP"TRUE";
"B \NAC \NWC"6;
"S \NAC"
BN"1"68;
%"TAP"
"1","(-5850,5750)","2","mstr_standard","I255";
;
CDS_LIB"mstr_standard"
BODY_TYPE"PLUMBING"
HDL_TAP"TRUE";
"B \NAC \NWC"6;
"S \NAC"
BN"2"67;
%"TAP"
"1","(-5850,5650)","2","mstr_standard","I256";
;
CDS_LIB"mstr_standard"
BODY_TYPE"PLUMBING"
HDL_TAP"TRUE";
"B \NAC \NWC"6;
"S \NAC"
BN"3"66;
%"TAP"
"1","(-5850,5450)","2","mstr_standard","I257";
;
CDS_LIB"mstr_standard"
BODY_TYPE"PLUMBING"
HDL_TAP"TRUE";
"B \NAC \NWC"6;
"S \NAC"
BN"5"64;
%"TAP"
"1","(-5850,5550)","2","mstr_standard","I258";
;
CDS_LIB"mstr_standard"
BODY_TYPE"PLUMBING"
HDL_TAP"TRUE";
"B \NAC \NWC"6;
"S \NAC"
BN"4"65;
%"TAP"
"1","(-5850,5350)","2","mstr_standard","I259";
;
CDS_LIB"mstr_standard"
BODY_TYPE"PLUMBING"
HDL_TAP"TRUE";
"B \NAC \NWC"6;
"S \NAC"
BN"6"63;
%"TAP"
"1","(-5850,5250)","2","mstr_standard","I260";
;
CDS_LIB"mstr_standard"
BODY_TYPE"PLUMBING"
HDL_TAP"TRUE";
"B \NAC \NWC"6;
"S \NAC"
BN"7"62;
%"TAP"
"1","(-5850,5150)","2","mstr_standard","I261";
;
CDS_LIB"mstr_standard"
BODY_TYPE"PLUMBING"
HDL_TAP"TRUE";
"B \NAC \NWC"6;
"S \NAC"
BN"8"61;
%"TAP"
"1","(-5650,5100)","2","mstr_standard","I262";
;
CDS_LIB"mstr_standard"
BODY_TYPE"PLUMBING"
HDL_TAP"TRUE";
"B \NAC \NWC"5;
"S \NAC"
BN"9"56;
%"TAP"
"1","(-5650,4950)","2","mstr_standard","I263";
;
CDS_LIB"mstr_standard"
BODY_TYPE"PLUMBING"
HDL_TAP"TRUE";
"B \NAC \NWC"7;
"S \NAC"
BN"0"60;
%"TAP"
"1","(-5650,4850)","2","mstr_standard","I264";
;
CDS_LIB"mstr_standard"
BODY_TYPE"PLUMBING"
HDL_TAP"TRUE";
"B \NAC \NWC"7;
"S \NAC"
BN"1"59;
%"TAP"
"1","(-5650,4750)","2","mstr_standard","I265";
;
CDS_LIB"mstr_standard"
BODY_TYPE"PLUMBING"
HDL_TAP"TRUE";
"B \NAC \NWC"7;
"S \NAC"
BN"2"58;
%"TAP"
"1","(-5650,4650)","2","mstr_standard","I266";
;
CDS_LIB"mstr_standard"
BODY_TYPE"PLUMBING"
HDL_TAP"TRUE";
"B \NAC \NWC"7;
"S \NAC"
BN"3"57;
%"TAP"
"1","(-5650,4550)","2","mstr_standard","I267";
;
CDS_LIB"mstr_standard"
BODY_TYPE"PLUMBING"
HDL_TAP"TRUE";
"B \NAC \NWC"7;
"S \NAC"
BN"4"51;
%"TAP"
"1","(-5650,4450)","2","mstr_standard","I268";
;
CDS_LIB"mstr_standard"
BODY_TYPE"PLUMBING"
HDL_TAP"TRUE";
"B \NAC \NWC"7;
"S \NAC"
BN"5"55;
%"TAP"
"1","(-5650,4350)","2","mstr_standard","I269";
;
CDS_LIB"mstr_standard"
BODY_TYPE"PLUMBING"
HDL_TAP"TRUE";
"B \NAC \NWC"7;
"S \NAC"
BN"6"54;
%"TAP"
"1","(-5650,4250)","2","mstr_standard","I270";
;
CDS_LIB"mstr_standard"
BODY_TYPE"PLUMBING"
HDL_TAP"TRUE";
"B \NAC \NWC"7;
"S \NAC"
BN"7"53;
%"TAP"
"1","(-5650,4150)","2","mstr_standard","I271";
;
CDS_LIB"mstr_standard"
BODY_TYPE"PLUMBING"
HDL_TAP"TRUE";
"B \NAC \NWC"7;
"S \NAC"
BN"8"52;
%"TAP"
"1","(-5850,4900)","2","mstr_standard","I272";
;
CDS_LIB"mstr_standard"
BODY_TYPE"PLUMBING"
HDL_TAP"TRUE";
"B \NAC \NWC"8;
"S \NAC"
BN"0"50;
%"TAP"
"1","(-5850,5050)","2","mstr_standard","I273";
;
CDS_LIB"mstr_standard"
BODY_TYPE"PLUMBING"
HDL_TAP"TRUE";
"B \NAC \NWC"6;
"S \NAC"
BN"9"46;
%"TAP"
"1","(-5850,4800)","2","mstr_standard","I274";
;
CDS_LIB"mstr_standard"
BODY_TYPE"PLUMBING"
HDL_TAP"TRUE";
"B \NAC \NWC"8;
"S \NAC"
BN"1"49;
%"TAP"
"1","(-5850,4700)","2","mstr_standard","I275";
;
CDS_LIB"mstr_standard"
BODY_TYPE"PLUMBING"
HDL_TAP"TRUE";
"B \NAC \NWC"8;
"S \NAC"
BN"2"48;
%"TAP"
"1","(-5850,4600)","2","mstr_standard","I276";
;
CDS_LIB"mstr_standard"
BODY_TYPE"PLUMBING"
HDL_TAP"TRUE";
"B \NAC \NWC"8;
"S \NAC"
BN"3"47;
%"TAP"
"1","(-5850,4500)","2","mstr_standard","I277";
;
CDS_LIB"mstr_standard"
BODY_TYPE"PLUMBING"
HDL_TAP"TRUE";
"B \NAC \NWC"8;
"S \NAC"
BN"4"45;
%"TAP"
"1","(-5850,4400)","2","mstr_standard","I278";
;
CDS_LIB"mstr_standard"
BODY_TYPE"PLUMBING"
HDL_TAP"TRUE";
"B \NAC \NWC"8;
"S \NAC"
BN"5"44;
%"TAP"
"1","(-5850,4300)","2","mstr_standard","I279";
;
CDS_LIB"mstr_standard"
BODY_TYPE"PLUMBING"
HDL_TAP"TRUE";
"B \NAC \NWC"8;
"S \NAC"
BN"6"43;
%"TAP"
"1","(-5850,4200)","2","mstr_standard","I280";
;
CDS_LIB"mstr_standard"
BODY_TYPE"PLUMBING"
HDL_TAP"TRUE";
"B \NAC \NWC"8;
"S \NAC"
BN"7"42;
%"TAP"
"1","(-5850,4100)","2","mstr_standard","I281";
;
CDS_LIB"mstr_standard"
BODY_TYPE"PLUMBING"
HDL_TAP"TRUE";
"B \NAC \NWC"8;
"S \NAC"
BN"8"41;
%"TAP"
"1","(-5650,4050)","2","mstr_standard","I286";
;
CDS_LIB"mstr_standard"
BODY_TYPE"PLUMBING"
HDL_TAP"TRUE";
"B \NAC \NWC"7;
"S \NAC"
BN"9"40;
%"TAP"
"1","(-5850,4000)","2","mstr_standard","I287";
;
CDS_LIB"mstr_standard"
BODY_TYPE"PLUMBING"
HDL_TAP"TRUE";
"B \NAC \NWC"8;
"S \NAC"
BN"9"39;
%"TAP"
"1","(-5850,3850)","2","mstr_standard","I288";
;
CDS_LIB"mstr_standard"
BODY_TYPE"PLUMBING"
HDL_TAP"TRUE";
"B \NAC \NWC"10;
"S \NAC"
BN"0"27;
%"TAP"
"1","(-5850,3750)","2","mstr_standard","I289";
;
CDS_LIB"mstr_standard"
BODY_TYPE"PLUMBING"
HDL_TAP"TRUE";
"B \NAC \NWC"10;
"S \NAC"
BN"2"37;
%"TAP"
"1","(-5850,3800)","2","mstr_standard","I290";
;
CDS_LIB"mstr_standard"
BODY_TYPE"PLUMBING"
HDL_TAP"TRUE";
"B \NAC \NWC"10;
"S \NAC"
BN"1"25;
%"TAP"
"1","(-5850,3700)","2","mstr_standard","I291";
;
CDS_LIB"mstr_standard"
BODY_TYPE"PLUMBING"
HDL_TAP"TRUE";
"B \NAC \NWC"10;
"S \NAC"
BN"3"35;
%"TAP"
"1","(-5850,3650)","2","mstr_standard","I292";
;
CDS_LIB"mstr_standard"
BODY_TYPE"PLUMBING"
HDL_TAP"TRUE";
"B \NAC \NWC"10;
"S \NAC"
BN"4"33;
%"TAP"
"1","(-5850,3600)","2","mstr_standard","I293";
;
CDS_LIB"mstr_standard"
BODY_TYPE"PLUMBING"
HDL_TAP"TRUE";
"B \NAC \NWC"10;
"S \NAC"
BN"5"31;
%"TAP"
"1","(-5850,3350)","2","mstr_standard","I294";
;
CDS_LIB"mstr_standard"
BODY_TYPE"PLUMBING"
HDL_TAP"TRUE";
"B \NAC \NWC"9;
"S \NAC"
BN"2"36;
%"TAP"
"1","(-5850,3550)","2","mstr_standard","I295";
;
CDS_LIB"mstr_standard"
BODY_TYPE"PLUMBING"
HDL_TAP"TRUE";
"B \NAC \NWC"10;
"S \NAC"
BN"6"29;
%"TAP"
"1","(-5850,3450)","2","mstr_standard","I296";
;
CDS_LIB"mstr_standard"
BODY_TYPE"PLUMBING"
HDL_TAP"TRUE";
"B \NAC \NWC"9;
"S \NAC"
BN"0"26;
%"TAP"
"1","(-5850,3400)","2","mstr_standard","I297";
;
CDS_LIB"mstr_standard"
BODY_TYPE"PLUMBING"
HDL_TAP"TRUE";
"B \NAC \NWC"9;
"S \NAC"
BN"1"38;
%"TAP"
"1","(-5850,3200)","2","mstr_standard","I298";
;
CDS_LIB"mstr_standard"
BODY_TYPE"PLUMBING"
HDL_TAP"TRUE";
"B \NAC \NWC"9;
"S \NAC"
BN"5"30;
%"TAP"
"1","(-5850,3300)","2","mstr_standard","I299";
;
CDS_LIB"mstr_standard"
BODY_TYPE"PLUMBING"
HDL_TAP"TRUE";
"B \NAC \NWC"9;
"S \NAC"
BN"3"34;
%"TAP"
"1","(-5850,3250)","2","mstr_standard","I300";
;
CDS_LIB"mstr_standard"
BODY_TYPE"PLUMBING"
HDL_TAP"TRUE";
"B \NAC \NWC"9;
"S \NAC"
BN"4"32;
%"TAP"
"1","(-5850,3150)","2","mstr_standard","I301";
;
CDS_LIB"mstr_standard"
BODY_TYPE"PLUMBING"
HDL_TAP"TRUE";
"B \NAC \NWC"9;
"S \NAC"
BN"6"28;
%"Q_RES"
"1","(-6775,2150)","0","pure_quanta","I314";
;
LOCATION"R386"
$SEC"1"
CDS_SEC"1"
PACK_TYPE"0402LF"
TOLERANCE"1%"
VALUE"15"
MATERIAL"CHIP"
WATTAGE"1/16W"
CDS_LIB"pure_quanta"
PART_NUMBER"CS01502FB03";
"B"
$PN"2"12;
"A"
$PN"1"11;
END.
